(kicad_pcb
	(version 20260206)
	(generator "pcbnew")
	(generator_version "10.0")
	(general
		(thickness 1.6)
		(legacy_teardrops no)
	)
	(paper "A4")
	(title_block
		(title "Bryce Canyon_F.DPB_16315-1-OCP.brd")
		(comment 1 "Bryce Canyon / footprints 2141-2148 of 2223")
	)
	(layers
		(0 "F.Cu" signal "TOP")
		(4 "In1.Cu" signal "L2GND")
		(6 "In2.Cu" signal "L3")
		(8 "In3.Cu" signal "L4GND")
		(10 "In4.Cu" signal "L5")
		(12 "In5.Cu" signal "L6VCC")
		(14 "In6.Cu" signal "L7VCC")
		(16 "In7.Cu" signal "L8")
		(18 "In8.Cu" signal "L9GND")
		(20 "In9.Cu" signal "L10")
		(22 "In10.Cu" signal "L11GND")
		(2 "B.Cu" signal "BOTTOM")
		(9 "F.Adhes" user "F.Adhesive")
		(11 "B.Adhes" user "B.Adhesive")
		(13 "F.Paste" user "Package Geometry/Pastemask Top")
		(15 "B.Paste" user "Package Geometry/Pastemask Bottom")
		(5 "F.SilkS" user "Ref Des/Silkscreen Top")
		(7 "B.SilkS" user "Ref Des/Silkscreen Bottom")
		(1 "F.Mask" user "Board Geometry/Soldermask Top")
		(3 "B.Mask" user "Board Geometry/Soldermask Bottom")
		(17 "Dwgs.User" user "User.Drawings")
		(19 "Cmts.User" user "User.Comments")
		(21 "Eco1.User" user "User.Eco1")
		(23 "Eco2.User" user "User.Eco2")
		(25 "Edge.Cuts" user "Board Geometry/Outline")
		(27 "Margin" user)
		(31 "F.CrtYd" user "Package Geometry/Place Bound Top")
		(29 "B.CrtYd" user "Package Geometry/Place Bound Bottom")
		(35 "F.Fab" user "Ref Des/Assembly Top")
		(33 "B.Fab" user "Ref Des/Assembly Bottom")
	)
	(footprint ""
		(layer "B.Cu")
		(at 32.274002 -254.43815 90)
		(property "Reference" "C665"
			(at 0 0 90)
			(layer "B.SilkS")
			(hide yes)
			(effects
				(font
					(size 1.27 1.27)
				)
				(justify mirror)
			)
		)
		(property "Value" "SC68P50V2JN-2-GP"
			(at -1.1811 -2.7051 90)
			(unlocked yes)
			(layer "B.Fab")
			(hide yes)
			(effects
				(font
					(size 1.016 1.016)
					(thickness 0.1524)
				)
				(justify mirror)
			)
		)
		(property "Device Type" "C402H22"
			(at -1.1811 -4.2291 90)
			(unlocked yes)
			(layer "B.Fab")
			(hide yes)
			(effects
				(font
					(size 1.016 1.016)
					(thickness 0.1524)
				)
				(justify mirror)
			)
		)
		(duplicate_pad_numbers_are_jumpers no)
		(fp_rect
			(start 0.4318 0.9525)
			(end -0.4318 -0.9525)
			(stroke
				(width 0)
				(type default)
			)
			(fill no)
			(layer "B.CrtYd")
		)
		(fp_rect
			(start 0.4318 0.9525)
			(end -0.4318 -0.9525)
			(stroke
				(width 0)
				(type default)
			)
			(fill no)
			(layer "B.Fab")
		)
		(pad "1" smd custom
			(at 0 -0.4445 270)
			(size 0.1524 0.1524)
			(layers "B.Cu" "B.Mask" "B.Paste")
			(net "P5V_A_VFB")
			(options
				(clearance outline)
				(anchor circle)
			)
			(primitives
				(gr_poly
					(pts
						(arc
							(start 0.3048 0.2032)
							(mid 0.275042 0.275042)
							(end 0.2032 0.3048)
						)
						(arc
							(start -0.2032 0.3048)
							(mid -0.275042 0.275042)
							(end -0.3048 0.2032)
						)
						(arc
							(start -0.3048 -0.2032)
							(mid -0.275042 -0.275042)
							(end -0.2032 -0.3048)
						)
						(arc
							(start 0.2032 -0.3048)
							(mid 0.275042 -0.275042)
							(end 0.3048 -0.2032)
						)
					)
					(width 0)
					(fill yes)
				)
			)
		)
		(pad "2" smd custom
			(at 0 0.4445 270)
			(size 0.1524 0.1524)
			(layers "B.Cu" "B.Mask" "B.Paste")
			(net "P5V_A_VFB_R")
			(options
				(clearance outline)
				(anchor circle)
			)
			(primitives
				(gr_poly
					(pts
						(arc
							(start 0.3048 0.2032)
							(mid 0.275042 0.275042)
							(end 0.2032 0.3048)
						)
						(arc
							(start -0.2032 0.3048)
							(mid -0.275042 0.275042)
							(end -0.3048 0.2032)
						)
						(arc
							(start -0.3048 -0.2032)
							(mid -0.275042 -0.275042)
							(end -0.2032 -0.3048)
						)
						(arc
							(start 0.2032 -0.3048)
							(mid 0.275042 -0.275042)
							(end 0.3048 -0.2032)
						)
					)
					(width 0)
					(fill yes)
				)
			)
		)
	)
	(footprint ""
		(layer "B.Cu")
		(at 218.821 -119.761 -90)
		(property "Reference" "U49"
			(at 0 0 90)
			(layer "B.SilkS")
			(hide yes)
			(effects
				(font
					(size 1.27 1.27)
				)
				(justify mirror)
			)
		)
		(property "Value" "TXS0102QDCURQ1-GP"
			(at 0 -11.1252 270)
			(unlocked yes)
			(layer "B.Fab")
			(hide yes)
			(effects
				(font
					(size 1.016 1.016)
					(thickness 0.1524)
				)
				(justify mirror)
			)
		)
		(property "Device Type" "SSOIC8-4H36"
			(at 0 -12.6492 270)
			(unlocked yes)
			(layer "B.Fab")
			(hide yes)
			(effects
				(font
					(size 1.016 1.016)
					(thickness 0.1524)
				)
				(justify mirror)
			)
		)
		(duplicate_pad_numbers_are_jumpers no)
		(fp_line
			(start -1.2573 2.1844)
			(end 1.2573 2.1844)
			(stroke
				(width 0.1524)
				(type default)
			)
			(layer "B.SilkS")
		)
		(fp_line
			(start 1.2573 2.1844)
			(end 1.2573 -2.1844)
			(stroke
				(width 0.1524)
				(type default)
			)
			(layer "B.SilkS")
		)
		(fp_line
			(start 1.2954 0.4572)
			(end 1.2954 2.159)
			(stroke
				(width 0.4064)
				(type default)
			)
			(layer "B.SilkS")
		)
		(fp_line
			(start 1.2065 0.2667)
			(end 1.27 0.2667)
			(stroke
				(width 0.1524)
				(type default)
			)
			(layer "B.SilkS")
		)
		(fp_line
			(start 0.9017 -0.0381)
			(end 1.2065 0.2667)
			(stroke
				(width 0.1524)
				(type default)
			)
			(layer "B.SilkS")
		)
		(fp_line
			(start 1.2192 -0.3556)
			(end 0.9017 -0.0381)
			(stroke
				(width 0.1524)
				(type default)
			)
			(layer "B.SilkS")
		)
		(fp_line
			(start 1.2573 -0.3556)
			(end 1.2192 -0.3556)
			(stroke
				(width 0.1524)
				(type default)
			)
			(layer "B.SilkS")
		)
		(fp_line
			(start -1.2573 -2.1844)
			(end -1.2573 2.1844)
			(stroke
				(width 0.1524)
				(type default)
			)
			(layer "B.SilkS")
		)
		(fp_line
			(start 1.2573 -2.1844)
			(end -1.2573 -2.1844)
			(stroke
				(width 0.1524)
				(type default)
			)
			(layer "B.SilkS")
		)
		(fp_poly
			(pts
				(xy 1.5113 2.4384) (xy -1.5113 2.4384) (xy -1.5113 -2.4384) (xy 1.5113 -2.4384)
			)
			(stroke
				(width 0)
				(type default)
			)
			(fill no)
			(layer "B.CrtYd")
		)
		(fp_poly
			(pts
				(xy 1.5113 -2.4384) (xy -1.5113 -2.4384) (xy -1.5113 2.4384) (xy 1.5113 2.4384)
			)
			(stroke
				(width 0)
				(type default)
			)
			(fill no)
			(layer "B.Fab")
		)
		(pad "1" smd rect
			(at 0.75057 1.1684 90)
			(size 0.3048 1.524)
			(layers "B.Cu" "B.Mask" "B.Paste")
			(net "I2C_BMC_A_COMP_A_SDA")
		)
		(pad "2" smd rect
			(at 0.25019 1.1684 90)
			(size 0.3048 1.524)
			(layers "B.Cu" "B.Mask" "B.Paste")
			(net "GND")
		)
		(pad "3" smd rect
			(at -0.25019 1.1684 90)
			(size 0.3048 1.524)
			(layers "B.Cu" "B.Mask" "B.Paste")
			(net "P3V3_STBY_A")
		)
		(pad "4" smd rect
			(at -0.75057 1.1684 90)
			(size 0.3048 1.524)
			(layers "B.Cu" "B.Mask" "B.Paste")
			(net "I2C_BMC_A_COMP_A_SDA_BUF")
		)
		(pad "5" smd rect
			(at -0.75057 -1.1684 90)
			(size 0.3048 1.524)
			(layers "B.Cu" "B.Mask" "B.Paste")
			(net "I2C_BMC_A_COMP_A_SCL_BUF")
		)
		(pad "6" smd rect
			(at -0.25019 -1.1684 90)
			(size 0.3048 1.524)
			(layers "B.Cu" "B.Mask" "B.Paste")
			(net "TXS0102_A_OE")
		)
		(pad "7" smd rect
			(at 0.25019 -1.1684 90)
			(size 0.3048 1.524)
			(layers "B.Cu" "B.Mask" "B.Paste")
			(net "P3V3_STBY_A")
		)
		(pad "8" smd rect
			(at 0.75057 -1.1684 90)
			(size 0.3048 1.524)
			(layers "B.Cu" "B.Mask" "B.Paste")
			(net "I2C_BMC_A_COMP_A_SCL")
		)
	)
	(footprint ""
		(layer "B.Cu")
		(at 182.39994 -208.499964 180)
		(property "Reference" "NUT7"
			(at 0 0 0)
			(layer "B.SilkS")
			(hide yes)
			(effects
				(font
					(size 1.27 1.27)
				)
				(justify mirror)
			)
		)
		(property "Value" "STF256R168H278-GP"
			(at 4.826 0.0508 180)
			(unlocked yes)
			(layer "B.Fab")
			(hide yes)
			(effects
				(font
					(size 1.016 1.016)
					(thickness 0.1524)
				)
				(justify mirror)
			)
		)
		(property "Device Type" "STF256R168H278"
			(at 4.826 -1.4732 180)
			(unlocked yes)
			(layer "B.Fab")
			(hide yes)
			(effects
				(font
					(size 1.016 1.016)
					(thickness 0.1524)
				)
				(justify mirror)
			)
		)
		(duplicate_pad_numbers_are_jumpers no)
		(fp_circle
			(center 0 0)
			(end -3.6068 0)
			(stroke
				(width 0.3048)
				(type default)
			)
			(fill no)
			(layer "B.SilkS")
		)
		(fp_poly
			(pts
				(arc
					(start -2.5019 0)
					(mid 2.5019 0)
					(end -2.5019 0)
				)
			)
			(stroke
				(width 0)
				(type default)
			)
			(fill no)
			(layer "B.CrtYd")
		)
		(fp_poly
			(pts
				(arc
					(start -3.7592 0.00635)
					(mid 3.759205 0)
					(end -3.7592 -0.00635)
				)
				(arc
					(start -2.5019 -0.00635)
					(mid 2.501908 0)
					(end -2.5019 0.00635)
				)
			)
			(stroke
				(width 0)
				(type default)
			)
			(fill no)
			(layer "B.CrtYd")
		)
		(fp_poly
			(pts
				(arc
					(start -3.7592 0)
					(mid 3.7592 0)
					(end -3.7592 0)
				)
			)
			(stroke
				(width 0)
				(type default)
			)
			(fill no)
			(layer "F.CrtYd")
		)
		(fp_poly
			(pts
				(arc
					(start -3.7592 0)
					(mid 3.7592 0)
					(end -3.7592 0)
				)
			)
			(stroke
				(width 0)
				(type default)
			)
			(fill no)
			(layer "B.Fab")
		)
		(fp_poly
			(pts
				(arc
					(start -3.7592 0)
					(mid 3.7592 0)
					(end -3.7592 0)
				)
			)
			(stroke
				(width 0)
				(type default)
			)
			(fill no)
			(layer "F.Fab")
		)
		(pad "1" thru_hole circle
			(at 0 0)
			(size 6.5024 6.5024)
			(drill 4.2672)
			(layers "*.Cu" "*.Mask")
			(remove_unused_layers no)
			(net "Net_5")
			(clearance -0.6096)
			(padstack
				(mode front_inner_back)
				(layer "Inner"
					(shape circle)
					(size 4.6736 4.6736)
					(clearance 0.3048)
				)
				(layer "B.Cu"
					(shape circle)
					(size 6.5024 6.5024)
					(thermal_gap 0.3048)
					(clearance -0.6096)
				)
			)
		)
	)
	(footprint ""
		(layer "B.Cu")
		(at 16.119602 -250.01855 180)
		(property "Reference" "R1206"
			(at 0 0 0)
			(layer "B.SilkS")
			(hide yes)
			(effects
				(font
					(size 1.27 1.27)
				)
				(justify mirror)
			)
		)
		(property "Value" "2D2R3-1-U-GP"
			(at 0.0254 -2.5146 180)
			(unlocked yes)
			(layer "B.Fab")
			(hide yes)
			(effects
				(font
					(size 1.016 1.016)
					(thickness 0.1524)
				)
				(justify mirror)
			)
		)
		(property "Device Type" "R603H22"
			(at 0.0254 -4.0386 180)
			(unlocked yes)
			(layer "B.Fab")
			(hide yes)
			(effects
				(font
					(size 1.016 1.016)
					(thickness 0.1524)
				)
				(justify mirror)
			)
		)
		(duplicate_pad_numbers_are_jumpers no)
		(fp_line
			(start 0.4826 0)
			(end 0.2032 0)
			(stroke
				(width 0.2032)
				(type default)
			)
			(layer "B.SilkS")
		)
		(fp_line
			(start -0.2032 0)
			(end -0.4826 0)
			(stroke
				(width 0.2032)
				(type default)
			)
			(layer "B.SilkS")
		)
		(fp_rect
			(start 0.5842 1.3335)
			(end -0.5842 -1.3335)
			(stroke
				(width 0)
				(type default)
			)
			(fill no)
			(layer "B.CrtYd")
		)
		(fp_rect
			(start 0.5842 1.3335)
			(end -0.5842 -1.3335)
			(stroke
				(width 0)
				(type default)
			)
			(fill no)
			(layer "B.Fab")
		)
		(pad "1" smd custom
			(at 0 -0.762)
			(size 0.2159 0.2159)
			(layers "B.Cu" "B.Mask" "B.Paste")
			(net "P12V_A")
			(options
				(clearance outline)
				(anchor circle)
			)
			(primitives
				(gr_poly
					(pts
						(arc
							(start -0.3302 0.4318)
							(mid -0.402042 0.402042)
							(end -0.4318 0.3302)
						)
						(arc
							(start -0.4318 -0.3302)
							(mid -0.402042 -0.402042)
							(end -0.3302 -0.4318)
						)
						(arc
							(start 0.3302 -0.4318)
							(mid 0.402042 -0.402042)
							(end 0.4318 -0.3302)
						)
						(arc
							(start 0.4318 0.3302)
							(mid 0.402042 0.402042)
							(end 0.3302 0.4318)
						)
					)
					(width 0)
					(fill yes)
				)
			)
		)
		(pad "2" smd custom
			(at 0 0.762)
			(size 0.2159 0.2159)
			(layers "B.Cu" "B.Mask" "B.Paste")
			(net "P12V_A_VDD_U20")
			(options
				(clearance outline)
				(anchor circle)
			)
			(primitives
				(gr_poly
					(pts
						(arc
							(start -0.3302 0.4318)
							(mid -0.402042 0.402042)
							(end -0.4318 0.3302)
						)
						(arc
							(start -0.4318 -0.3302)
							(mid -0.402042 -0.402042)
							(end -0.3302 -0.4318)
						)
						(arc
							(start 0.3302 -0.4318)
							(mid 0.402042 -0.402042)
							(end 0.4318 -0.3302)
						)
						(arc
							(start 0.4318 0.3302)
							(mid 0.402042 0.402042)
							(end 0.3302 0.4318)
						)
					)
					(width 0)
					(fill yes)
				)
			)
		)
	)
	(footprint ""
		(layer "B.Cu")
		(at 472.027504 -203.399898)
		(property "Reference" "PG16"
			(at 0 0 0)
			(layer "B.SilkS")
			(hide yes)
			(effects
				(font
					(size 1.27 1.27)
				)
				(justify mirror)
			)
		)
		(property "Value" "GAP-CLOSE-PWR-4-GP"
			(at 2.4638 -0.5461 0)
			(unlocked yes)
			(layer "B.Fab")
			(hide yes)
			(effects
				(font
					(size 1.016 1.016)
					(thickness 0.1524)
				)
				(justify mirror)
			)
		)
		(property "Device Type" "GAP-CLOSE-PWR-4"
			(at 2.4638 -2.0701 0)
			(unlocked yes)
			(layer "B.Fab")
			(hide yes)
			(effects
				(font
					(size 1.016 1.016)
					(thickness 0.1524)
				)
				(justify mirror)
			)
		)
		(duplicate_pad_numbers_are_jumpers no)
		(fp_rect
			(start 0.2794 0.254)
			(end -0.2794 -0.254)
			(stroke
				(width 0)
				(type default)
			)
			(fill no)
			(layer "B.CrtYd")
		)
		(fp_rect
			(start 0.2794 0.254)
			(end -0.2794 -0.254)
			(stroke
				(width 0)
				(type default)
			)
			(fill no)
			(layer "B.Fab")
		)
		(pad "1" smd rect
			(at 0.0635 0 180)
			(size 0.1778 0.254)
			(layers "B.Cu" "B.Mask" "B.Paste")
			(net "P5V_A_4")
		)
		(pad "2" smd rect
			(at -0.0635 0 180)
			(size 0.1778 0.254)
			(layers "B.Cu" "B.Mask" "B.Paste")
			(net "P5V_D_CC")
		)
	)
	(footprint ""
		(layer "B.Cu")
		(at 183.151526 -219.93987 -90)
		(property "Reference" "G1"
			(at 0 0 90)
			(layer "B.SilkS")
			(hide yes)
			(effects
				(font
					(size 1.27 1.27)
				)
				(justify mirror)
			)
		)
		(property "Value" "COPPER-CLOSE-GP-U"
			(at -0.0762 -2.8702 270)
			(unlocked yes)
			(layer "B.Fab")
			(hide yes)
			(effects
				(font
					(size 1.016 1.016)
					(thickness 0.1524)
				)
				(justify mirror)
			)
		)
		(property "Device Type" "CON2C-U"
			(at -0.0762 -4.3942 270)
			(unlocked yes)
			(layer "B.Fab")
			(hide yes)
			(effects
				(font
					(size 1.016 1.016)
					(thickness 0.1524)
				)
				(justify mirror)
			)
		)
		(duplicate_pad_numbers_are_jumpers no)
		(fp_rect
			(start 0.9398 0.9652)
			(end -0.9398 -0.9652)
			(stroke
				(width 0)
				(type default)
			)
			(fill no)
			(layer "B.CrtYd")
		)
		(fp_rect
			(start 0.9398 0.9652)
			(end -0.9398 -0.9652)
			(stroke
				(width 0)
				(type default)
			)
			(fill no)
			(layer "B.Fab")
		)
		(pad "1" smd custom
			(at 0 -0.5334 90)
			(size 0.17145 0.17145)
			(layers "B.Cu" "B.Mask" "B.Paste")
			(net "AGND_P3V3_STBY")
			(options
				(clearance outline)
				(anchor circle)
			)
			(primitives
				(gr_poly
					(pts
						(xy -0.127 -0.3429) (xy -0.127 -0.1651) (xy -0.635 0.3429) (xy 0.635 0.3429) (xy 0.127 -0.1651)
						(xy 0.127 -0.3429)
					)
					(width 0)
					(fill yes)
				)
			)
		)
		(pad "2" smd custom
			(at 0 0.5334 90)
			(size 0.17145 0.17145)
			(layers "B.Cu" "B.Mask" "B.Paste")
			(net "GND")
			(options
				(clearance outline)
				(anchor circle)
			)
			(primitives
				(gr_poly
					(pts
						(xy -0.635 -0.3429) (xy -0.127 0.1651) (xy -0.127 0.3429) (xy 0.127 0.3429) (xy 0.127 0.1651)
						(xy 0.635 -0.3429)
					)
					(width 0)
					(fill yes)
				)
			)
		)
	)
	(footprint ""
		(layer "B.Cu")
		(at 127.824992 -210.799934 180)
		(property "Reference" "SCW1"
			(at 0 0 0)
			(layer "B.SilkS")
			(hide yes)
			(effects
				(font
					(size 1.27 1.27)
				)
				(justify mirror)
			)
		)
		(property "Value" ""
			(at 0 0 0)
			(layer "B.Fab")
			(effects
				(font
					(size 1.27 1.27)
				)
				(justify mirror)
			)
		)
		(duplicate_pad_numbers_are_jumpers no)
		(fp_poly
			(pts
				(arc
					(start -5.4356 0)
					(mid 5.4356 0)
					(end -5.4356 0)
				)
			)
			(stroke
				(width 0)
				(type default)
			)
			(fill no)
			(layer "B.CrtYd")
		)
		(fp_poly
			(pts
				(arc
					(start -5.4356 0)
					(mid 5.4356 0)
					(end -5.4356 0)
				)
			)
			(stroke
				(width 0)
				(type default)
			)
			(fill no)
			(layer "F.CrtYd")
		)
		(fp_poly
			(pts
				(arc
					(start -5.4356 0)
					(mid 5.4356 0)
					(end -5.4356 0)
				)
			)
			(stroke
				(width 0)
				(type default)
			)
			(fill no)
			(layer "B.Fab")
		)
		(fp_poly
			(pts
				(arc
					(start -5.4356 0)
					(mid 5.4356 0)
					(end -5.4356 0)
				)
			)
			(stroke
				(width 0)
				(type default)
			)
			(fill no)
			(layer "F.Fab")
		)
		(pad "" np_thru_hole circle
			(at 0 0)
			(size 0.254 0.254)
			(drill 10.2616)
			(layers "*.Cu" "*.Mask")
			(clearance 5.3594)
			(thermal_gap 5.3594)
		)
		(zone
			(layers "F.Cu" "B.Cu" "In1.Cu" "In2.Cu" "In3.Cu" "In4.Cu" "In5.Cu" "In6.Cu"
				"In7.Cu" "In8.Cu" "In9.Cu" "In10.Cu"
			)
			(hatch none 0.5)
			(connect_pads
				(clearance 0)
			)
			(min_thickness 0.25)
			(keepout
				(tracks not_allowed)
				(vias allowed)
				(pads allowed)
				(copperpour not_allowed)
				(footprints allowed)
			)
			(placement
				(enabled no)
				(sheetname "")
			)
			(fill
				(thermal_gap 0.5)
				(thermal_bridge_width 0.5)
				(island_removal_mode 0)
			)
			(polygon
				(pts
					(arc
						(start 133.260592 -210.799934)
						(mid 122.389392 -210.799934)
						(end 133.260592 -210.799934)
					)
				)
			)
		)
	)
	(footprint ""
		(layer "B.Cu")
		(at 40.714422 -144.57553 90)
		(property "Reference" "C625"
			(at 0 0 90)
			(layer "B.SilkS")
			(hide yes)
			(effects
				(font
					(size 1.27 1.27)
				)
				(justify mirror)
			)
		)
		(property "Value" "SC1U16V3KX-5GP"
			(at 0 -2.8194 90)
			(unlocked yes)
			(layer "B.Fab")
			(hide yes)
			(effects
				(font
					(size 1.016 1.016)
					(thickness 0.1524)
				)
				(justify mirror)
			)
		)
		(property "Device Type" "C603H36"
			(at 0 -4.3434 90)
			(unlocked yes)
			(layer "B.Fab")
			(hide yes)
			(effects
				(font
					(size 1.016 1.016)
					(thickness 0.1524)
				)
				(justify mirror)
			)
		)
		(duplicate_pad_numbers_are_jumpers no)
		(fp_line
			(start -0.508 0)
			(end 0.508 0)
			(stroke
				(width 0.2032)
				(type default)
			)
			(layer "B.SilkS")
		)
		(fp_rect
			(start 0.5842 1.3335)
			(end -0.5842 -1.3335)
			(stroke
				(width 0)
				(type default)
			)
			(fill no)
			(layer "B.CrtYd")
		)
		(fp_rect
			(start 0.5842 1.3335)
			(end -0.5842 -1.3335)
			(stroke
				(width 0)
				(type default)
			)
			(fill no)
			(layer "B.Fab")
		)
		(pad "1" smd custom
			(at 0 -0.762 270)
			(size 0.2159 0.2159)
			(layers "B.Cu" "B.Mask" "B.Paste")
			(net "GND")
			(options
				(clearance outline)
				(anchor circle)
			)
			(primitives
				(gr_poly
					(pts
						(arc
							(start -0.3302 0.4318)
							(mid -0.402042 0.402042)
							(end -0.4318 0.3302)
						)
						(arc
							(start -0.4318 -0.3302)
							(mid -0.402042 -0.402042)
							(end -0.3302 -0.4318)
						)
						(arc
							(start 0.3302 -0.4318)
							(mid 0.402042 -0.402042)
							(end 0.4318 -0.3302)
						)
						(arc
							(start 0.4318 0.3302)
							(mid 0.402042 0.402042)
							(end 0.3302 0.4318)
						)
					)
					(width 0)
					(fill yes)
				)
			)
		)
		(pad "2" smd custom
			(at 0 0.762 270)
			(size 0.2159 0.2159)
			(layers "B.Cu" "B.Mask" "B.Paste")
			(net "P5V_B_VREG")
			(options
				(clearance outline)
				(anchor circle)
			)
			(primitives
				(gr_poly
					(pts
						(arc
							(start -0.3302 0.4318)
							(mid -0.402042 0.402042)
							(end -0.4318 0.3302)
						)
						(arc
							(start -0.4318 -0.3302)
							(mid -0.402042 -0.402042)
							(end -0.3302 -0.4318)
						)
						(arc
							(start 0.3302 -0.4318)
							(mid 0.402042 -0.402042)
							(end 0.4318 -0.3302)
						)
						(arc
							(start 0.4318 0.3302)
							(mid 0.402042 0.402042)
							(end 0.3302 0.4318)
						)
					)
					(width 0)
					(fill yes)
				)
			)
		)
	)
)
